#ISCELL
  pure_quanta quanta_title_block_c *
  *
#ISCELL
  standard offpage *
  page374_i1
#ISCELL
  pure_quanta_power universal_gnd *
  page374_i10
#CELL
  pure_quanta q_led *
  page374_i11
#CELL
  pure_quanta q_res *
  page374_i12
#CELL
  pure_quanta q_led *
  page374_i13
#CELL
  pure_quanta q_led *
  page374_i14
#CELL
  pure_quanta q_res *
  page374_i15
#CELL
  pure_quanta q_res *
  page374_i16
#ISCELL
  standard offpage *
  page374_i17
#CELL
  pure_quanta mosfet_nch_dual *
  page374_i18
#CELL
  pure_quanta q_led *
  page374_i19
#ISCELL
  standard offpage *
  page374_i2
#CELL
  pure_quanta q_res *
  page374_i20
#ISCELL
  pure_quanta_power universal_power *
  page374_i21
#ISCELL
  standard offpage *
  page374_i22
#CELL
  pure_quanta mosfet_nch_dual *
  page374_i23
#ISCELL
  pure_quanta_power universal_power *
  page374_i24
#ISCELL
  standard offpage *
  page374_i25
#ISCELL
  pure_quanta_power universal_power *
  page374_i26
#CELL
  pure_quanta mosfet_nch_dual *
  page374_i27
#ISCELL
  pure_quanta_power universal_gnd *
  page374_i28
#ISCELL
  pure_quanta_power universal_gnd *
  page374_i29
#CELL
  pure_quanta mosfet_nch_dual *
  page374_i3
#CELL
  pure_quanta q_led *
  page374_i30
#ISCELL
  pure_quanta_power universal_gnd *
  page374_i31
#CELL
  pure_quanta q_led *
  page374_i32
#ISCELL
  pure_quanta_power universal_power *
  page374_i33
#ISCELL
  standard offpage *
  page374_i34
#CELL
  pure_quanta mosfet_nch_dual *
  page374_i35
#CELL
  pure_quanta q_led *
  page374_i36
#CELL
  pure_quanta q_res *
  page374_i37
#CELL
  pure_quanta q_res *
  page374_i38
#ISCELL
  pure_quanta_power universal_power *
  page374_i39
#ISCELL
  pure_quanta_power universal_gnd *
  page374_i4
#ISCELL
  pure_quanta_power universal_power *
  page374_i40
#CELL
  pure_quanta q_res *
  page374_i41
#ISCELL
  pure_quanta_power universal_power *
  page374_i42
#CELL
  pure_quanta mosfet_nch_dual *
  page374_i43
#ISCELL
  pure_quanta_power universal_gnd *
  page374_i5
#CELL
  pure_quanta mosfet_nch_dual *
  page374_i6
#ISCELL
  standard offpage *
  page374_i7
#CELL
  pure_quanta mosfet_nch_dual *
  page374_i8
#ISCELL
  pure_quanta_power universal_gnd *
  page374_i9
